FILE_TYPE = CONNECTIVITY;
{Allegro Design Entry HDL 17.2-2016 S081 (4005846) 1/11/2022}
"PAGE_NUMBER" = 182;
0"NC";
1"P3V3_AUX\g";
2"P3V3_AUX\g";
3"P3V3_AUX\g";
4"P3V3_M2_0\g";
5"P3V3_AUX\g";
6"P3V3_AUX\g";
7"P3V3_AUX\g";
8"P3V3_M2_0\g";
9"P3V3_M2_0\g";
10"P3V3_AUX\g";
11"P3V3_AUX\g";
12"GND\g";
13"GND\g";
14"GND\g";
15"GND\g";
16"GND\g";
17"GND\g";
18"GND\g";
19"GND\g";
20"GND\g";
21"GND\g";
22"P3E_PCH_M2_RX_DP<2:0>";
23"P3E_PCH_M2_TX_C_DN<2:0>";
24"P3E_PCH_M2_TX_C_DP<2:0>";
25"P3E_PCH_M2_RX_DN<2:0>";
26"P3E_PCH_M2_RX_DN<0>";
27"P3E_PCH_M2_RX_DP<1>";
28"P3E_PCH_M2_TX_C_DN<1>";
29"P3E_PCH_M2_TX_C_DP<1>";
30"NC_M2_0_NC1";
31"NC_M2_0_NC2";
32"NC_M2_0_NC5";
33"NC_M2_0_NC9";
34"NC_M2_0_NC14";
35"FM_M2_SSD_0_PEDET";
36"LED_M2_SSD_0_ACT_N";
37"NC_M2_0_SUSCLK"CDS_PHYS_NET_NAME"NC_M2_1_SUSCLK";
38"P3E_PCH_M2_RX_DP<3>";
39"LED_HDD_ACTIVITY_B_N";
40"M2_SSD0_CLKREQ_EN_N_BUF";
41"M2_0_PEWAKE_N"CDS_PHYS_NET_NAME"NC_M2_1_PEWAKE_N";
42"RST_PCIE_PCH_DEV_BUF_M2_0_PERST_N"CDS_PHYS_NET_NAME"RST_PCIE_CPU0_BUF_E1S_0_PERST_N";
43"RST_PCIE_PCH_DEV_0_N";
44"HDD_ACTIVITY_BUF_N";
45"CLK_100M_PE_M2_0_DN";
46"RST_PCIE_PCH_DEV_0_N"CDS_PHYS_NET_NAME"RST_PCIE_PCH_DEV_0_N";
47"PD_M2_0_DEVSLP"CDS_PHYS_NET_NAME"NC_M2_1_SUSCLK";
48"P3E_PCH_M2_RX_DN<3>";
49"P3E_PCH_M2_TX_C_DP<3>";
50"NC_M2_0_NC19";
51"NC_M2_0_NC18";
52"NC_M2_0_NC17";
53"NC_M2_0_NC16";
54"HDD_ACTIVITY_BUF";
55"NC_Q95_G2";
56"NC_Q95_S2";
57"NC_Q95_D2";
58"NC_M2_0_NC3";
59"NC_M2_0_NC4";
60"NC_M2_0_NC8";
61"NC_M2_0_NC10";
62"NC_M2_0_NC15";
63"P3E_PCH_M2_TX_C_DN<3>";
64"SMB_M2_P0_1V8AUX_SDA"CDS_PHYS_NET_NAME"SMB_M2_P0_3V3AUX_SDA";
65"SMB_M2_P0_1V8AUX_SCL"CDS_PHYS_NET_NAME"SMB_M2_P0_3V3AUX_SCL";
66"NC_M2_0_NC11";
67"NC_M2_0_NC7";
68"NC_M2_0_NC6";
69"LED_M2_SSD_0_ACT_N";
70"PCIE_M2_SSD0_PRSNT_N";
71"LED_HDD_ACTIVITY_N";
72"PU_BUFFER_HDD_ACTIVITY";
73"M2_SSD0_CLKREQ_EN_N";
74"RST_PCIE_PCH_DEV_PERST_M2_R_N"CDS_PHYS_NET_NAME"RST_PCIE_CPU0_E1S_PERST_N";
75"CLK_100M_PE_M2_0_DP";
76"PU_BUFFER_HDD_ACTIVITY";
77"IRQ_LVC3_WAKE_N"CDS_PHYS_NET_NAME"RST_PCIE_PCH_DEV_PERST_N";
78"M2_SSD0_CLKREQ_EN_N";
79"FM_M2_SSD0_E7_PEDET";
80"P3E_PCH_M2_RX_DN<2>"$PNN"P3E_PCH_M2_RX_DN<2>";
81"P3E_PCH_M2_RX_DN<1>"$PNN"P3E_PCH_M2_RX_DN<1>";
82"P3E_PCH_M2_RX_DP<2>";
83"P3E_PCH_M2_TX_C_DP<2>";
84"P3E_PCH_M2_TX_C_DN<2>";
85"P3E_PCH_M2_TX_C_DP<0>";
86"P3E_PCH_M2_TX_C_DN<0>";
87"P3E_PCH_M2_RX_DP<0>";
88"PD_M2_0_DEVSLP";
%"Q_CAP"
"1","(13275,4275)","0","pure_quanta","I100";
;
PART_NUMBER"CH4104K1B00"
VALUE"0.1UF"
MATERIAL"X7R"
PACK_TYPE"0402"
VOLTAGE"25V"
TOLERANCE"10%"
LOCATION"C1925"
CDS_LIB"pure_quanta"
$SEC"1"
CDS_SEC"1";
"B"
$PN"2"20;
"A"
$PN"1"4;
%"Q_RES"
"2","(13350,2900)","0","pure_quanta","I105";
;
PART_NUMBER"CS21002FB06"
MATERIAL"CHIP"
WATTAGE"1/16W"
TOLERANCE"1%"
VALUE"1K"
PACK_TYPE"0402LF"
$LOCATION"R1605"
CDS_LIB"pure_quanta"
CDS_LOCATION"R1605"
$SEC"1"
CDS_SEC"1";
"A"
$PN"1"88;
"B"
$PN"2"18;
%"UNIVERSAL_GND"
"1","(13350,2650)","0","logical_power","I106";
;
CDS_LIB"logical_power"
HDL_POWER"GND";
"A"18;
%"TAP"
"1","(7725,3750)","2","standard","I136";
;
HDL_TAP"TRUE"
BODY_TYPE"PLUMBING"
CDS_LIB"standard";
"B \NAC \NWC"24;
"S \NAC"
BN"2"83;
%"TAP"
"1","(7575,3800)","2","standard","I137";
;
HDL_TAP"TRUE"
BODY_TYPE"PLUMBING"
CDS_LIB"standard";
"B \NAC \NWC"23;
"S \NAC"
BN"2"84;
%"TAP"
"1","(7725,4000)","2","standard","I146";
;
CDS_LIB"standard"
BODY_TYPE"PLUMBING"
HDL_TAP"TRUE";
"B \NAC \NWC"24;
"S \NAC"
BN"1"29;
%"TAP"
"1","(7575,4050)","2","standard","I147";
;
CDS_LIB"standard"
BODY_TYPE"PLUMBING"
HDL_TAP"TRUE";
"B \NAC \NWC"23;
"S \NAC"
BN"1"28;
%"TAP"
"1","(7725,4250)","2","standard","I150";
;
CDS_LIB"standard"
BODY_TYPE"PLUMBING"
HDL_TAP"TRUE";
"B \NAC \NWC"24;
"S \NAC"
BN"0"85;
%"TAP"
"1","(7575,4300)","2","standard","I151";
;
CDS_LIB"standard"
BODY_TYPE"PLUMBING"
HDL_TAP"TRUE";
"B \NAC \NWC"23;
"S \NAC"
BN"0"86;
%"Q_RES"
"1","(6425,3350)","0","pure_quanta","I162";
;
PART_NUMBER"CS00002JB13"
VALUE"0"
TOLERANCE"5%"
MATERIAL"CHIP"
$LOCATION"R486"
CDS_LIB"pure_quanta"
WATTAGE"1/16W"
PACK_TYPE"0402LF"
CDS_LOCATION"R486"
$SEC"1"
CDS_SEC"1";
"B"
$PN"2"40;
"A"
$PN"1"78;
%"Q_RES"
"2","(5450,3075)","0","pure_quanta","I164";
;
PART_NUMBER"CS24702FB06"
PACK_TYPE"0402LF"
VALUE"4.7K"
TOLERANCE"1%"
MATERIAL"EMPTY"
WATTAGE"1/16W"
$LOCATION"R491"
CDS_LIB"pure_quanta"
CDS_LOCATION"R491"
$SEC"1"
CDS_SEC"1";
"A"
$PN"1"78;
"B"
$PN"2"21;
%"UNIVERSAL_GND"
"1","(5450,2850)","0","logical_power","I165";
;
CDS_LIB"logical_power"
HDL_POWER"GND";
"A"21;
%"Q_RES"
"1","(10600,3275)","0","pure_quanta","I167";
;
PART_NUMBER"CS31002FB08"
WATTAGE"1/16W"
MATERIAL"CHIP"
TOLERANCE"1%"
VALUE"10K"
PACK_TYPE"0402LF"
$LOCATION"R1396"
CDS_LIB"pure_quanta"
CDS_LOCATION"R1396"
$SEC"1"
CDS_SEC"1";
"B"
$PN"2"5;
"A"
$PN"1"35;
%"UNIVERSAL_GND"
"1","(7975,2100)","0","logical_power","I172";
;
HDL_POWER"GND"
CDS_LIB"logical_power";
"A"19;
%"Q_RES"
"2","(6975,3925)","2","pure_quanta","I173";
;
PART_NUMBER"CS21002FB06"
PACK_TYPE"0402LF"
MATERIAL"CHIP"
TOLERANCE"1%"
WATTAGE"1/16W"
VALUE"1K"
$LOCATION"R487"
CDS_LIB"pure_quanta"
CDS_LOCATION"R487"
$SEC"1"
CDS_SEC"1";
"A"
$PN"1"3;
"B"
$PN"2"40;
%"UNIVERSAL_POWER"
"1","(6975,4150)","0","logical_power","I174";
;
HDL_POWER"P3V3_AUX"
CDS_LIB"logical_power";
"A"3;
%"Q_RES"
"2","(6975,2700)","0","pure_quanta","I176";
;
PART_NUMBER"CS24702FB06"
PACK_TYPE"0402LF"
MATERIAL"CHIP"
WATTAGE"1/16W"
VALUE"4.7K"
TOLERANCE"1%"
$LOCATION"R478"
CDS_LIB"pure_quanta"
CDS_LOCATION"R478"
$SEC"1"
CDS_SEC"1";
"A"
$PN"1"6;
"B"
$PN"2"70;
%"UNIVERSAL_POWER"
"1","(6975,2925)","0","logical_power","I177";
;
HDL_POWER"P3V3_AUX"
CDS_LIB"logical_power";
"A"6;
%"SCONN75K_APCI0155P004A"
"1","(8725,3325)","2","pure_quanta","I178";
;
PART_NUMBER"DFHS75FR313"
VALUE"SCONN75K_APCI0155-P004A"
PART_TYPE"SMLF"
MATERIAL"EMPTY"
$LOCATION"J59"
PIN_NAMES_ROTATE"True"
CDS_LMAN_SYM_OUTLINE"-450,1125,450,-1125"
CDS_LIB"pure_quanta"
CDS_LOCATION"J59"
$SEC"1"
CDS_SEC"1";
"REFCLKP"
$PN"55"75;
"REFCLKN"
$PN"53"45;
"PETP1"
$PN"37"84;
"PETN1"
$PN"35"83;
"PERP1"
$PN"31"82;
"PERN1"
$PN"29"80;
"PETP2"
$PN"25"28;
"PETN2"
$PN"23"29;
"PERP2"
$PN"19"27;
"PERN2"
$PN"17"81;
"PETP3"
$PN"13"86;
"PETN3"
$PN"11"85;
"PERP3"
$PN"7"87;
"PERN3"
$PN"5"26;
"GND10"
$PN"51"19;
"GND9"
$PN"45"19;
"GND8"
$PN"39"19;
"GND7"
$PN"33"19;
"GND6"
$PN"27"19;
"GND5"
$PN"21"19;
"GND4"
$PN"15"19;
"GND3"
$PN"9"19;
"GND2"
$PN"3"19;
"GND1"
$PN"1"70;
"NC4"
$PN"22"59;
"NC5"
$PN"24"32;
"NC6"
$PN"26"68;
"NC7"
$PN"28"67;
"NC8"
$PN"30"60;
"NC9"
$PN"32"33;
"NC11"
$PN"36"66;
"NC12"
$PN"40"65;
"NC13"
$PN"42"64;
"NC14"
$PN"44"34;
"NC15"
$PN"46"62;
"NC16"
$PN"48"53;
"NC17"
$PN"56"52;
"NC10"
$PN"34"61;
"NC3"
$PN"20"58;
"NC2"
$PN"8"31;
"NC1"
$PN"6"30;
"G2"
$PN"G2"19;
"G1"
$PN"G1"19;
"GND14"
$PN"75"19;
"GND13"
$PN"73"19;
"GND12"
$PN"71"19;
"PEDET"
$PN"69"35;
"NC19"
$PN"67"50;
"GND11"
$PN"57"19;
"PETP0||SATA-A+"
$PN"49"63;
"PETN0||SATA-A-"
$PN"47"49;
"PERP0||SATA-B-"
$PN"43"38;
"PERN0||SATA-B+"
$PN"41"48;
"3.3V_9"
$PN"74"8;
"3.3V_8"
$PN"72"8;
"3.3V_7"
$PN"70"8;
"SUSCLK"
$PN"68"37;
"NC18"
$PN"58"51;
"PEWAKE# \B"
$PN"54"41;
"CLKREQ# \B"
$PN"52"40;
"PERST# \B"
$PN"50"46;
"DEVSLP"
$PN"38"47;
"3.3V_6"
$PN"18"8;
"3.3V_5"
$PN"16"8;
"3.3V_4"
$PN"14"8;
"3.3V_3"
$PN"12"8;
"DAS_DSS#||LED1#"
$PN"10"36;
"3.3V_2"
$PN"4"8;
"3.3V_1"
$PN"2"8;
%"TAP"
"1","(7400,4400)","2","standard","I233";
;
HDL_TAP"TRUE"
BODY_TYPE"PLUMBING"
CDS_LIB"standard";
"B \NAC \NWC"22;
"S \NAC"
BN"0"87;
%"TAP"
"1","(7250,4350)","2","standard","I234";
;
HDL_TAP"TRUE"
BODY_TYPE"PLUMBING"
CDS_LIB"standard";
"B \NAC \NWC"25;
"S \NAC"
BN"0"26;
%"TAP"
"1","(7250,4100)","2","standard","I235";
;
HDL_TAP"TRUE"
BODY_TYPE"PLUMBING"
CDS_LIB"standard";
"B \NAC \NWC"25;
"S \NAC"
BN"1"81;
%"TAP"
"1","(7400,4150)","2","standard","I236";
;
HDL_TAP"TRUE"
BODY_TYPE"PLUMBING"
CDS_LIB"standard";
"B \NAC \NWC"22;
"S \NAC"
BN"1"27;
%"TAP"
"1","(7400,3900)","2","standard","I237";
;
HDL_TAP"TRUE"
BODY_TYPE"PLUMBING"
CDS_LIB"standard";
"B \NAC \NWC"22;
"S \NAC"
BN"2"82;
%"TAP"
"1","(7250,3850)","2","standard","I238";
;
HDL_TAP"TRUE"
BODY_TYPE"PLUMBING"
CDS_LIB"standard";
"B \NAC \NWC"25;
"S \NAC"
BN"2"80;
%"Q_RES"
"1","(10600,3500)","0","pure_quanta","I247";
;
PART_NUMBER"CS00002JB13"
TOLERANCE"5%"
VALUE"0"
MATERIAL"CHIP"
$LOCATION"R2526"
WATTAGE"1/16W"
PACK_TYPE"0402LF"
CDS_LIB"pure_quanta"
CDS_LOCATION"R2526"
$SEC"1"
CDS_SEC"1";
"B"
$PN"2"79;
"A"
$PN"1"35;
%"UNIVERSAL_POWER"
"1","(11175,3350)","0","logical_power","I249";
;
HDL_POWER"P3V3_AUX"
CDS_LIB"logical_power";
"A"5;
%"Q_RES"
"1","(6975,3300)","0","pure_quanta","I299";
;
PART_NUMBER"CS03322FB03"
VALUE"33.2"
TOLERANCE"1%"
MATERIAL"CHIP"
LOCATION"R3301"
PACK_TYPE"0402LF"
WATTAGE"1/16W"
CDS_LIB"pure_quanta"
$SEC"1"
CDS_SEC"1";
"B"
$PN"2"41;
"A"
$PN"1"77;
%"UNIVERSAL_POWER"
"1","(9475,4650)","0","logical_power","I300";
;
HDL_POWER"P3V3_M2_0"
CDS_LIB"logical_power";
"A"8;
%"UNIVERSAL_GND"
"1","(8050,-1050)","0","logical_power","I301";
;
HDL_POWER"GND"
CDS_LIB"logical_power";
"A"13;
%"Q_RES"
"2","(10300,925)","2","pure_quanta","I303";
;
PART_NUMBER"CS31002FB08"
WATTAGE"1/16W"
TOLERANCE"1%"
VALUE"10K"
MATERIAL"CHIP"
PACK_TYPE"0402LF"
$LOCATION"R3297"
CDS_LIB"pure_quanta"
CDS_LOCATION"R3297"
$SEC"1"
CDS_SEC"1";
"A"
$PN"1"39;
"B"
$PN"2"14;
%"UNIVERSAL_GND"
"1","(10300,675)","0","logical_power","I304";
;
CDS_LIB"logical_power"
HDL_POWER"GND";
"A"14;
%"UNIVERSAL_POWER"
"1","(10725,700)","0","logical_power","I305";
;
HDL_POWER"P3V3_AUX"
CDS_LIB"logical_power";
"A"10;
%"Q_RES"
"2","(10725,500)","2","pure_quanta","I306";
;
PART_NUMBER"CS31002FB08"
VALUE"10K"
MATERIAL"CHIP"
WATTAGE"1/16W"
PACK_TYPE"0402LF"
TOLERANCE"1%"
$LOCATION"R3298"
CDS_LIB"pure_quanta"
CDS_LOCATION"R3298"
$SEC"1"
CDS_SEC"1";
"A"
$PN"1"10;
"B"
$PN"2"44;
%"UNIVERSAL_POWER"
"1","(9350,1875)","0","logical_power","I307";
;
HDL_POWER"P3V3_AUX"
CDS_LIB"logical_power";
"A"11;
%"Q_CAP"
"1","(9600,1525)","0","pure_quanta","I308";
;
PART_NUMBER"CH4104K1B00"
MATERIAL"X7R"
PACK_TYPE"0402"
TOLERANCE"10%"
VOLTAGE"25V"
VALUE"0.1UF"
$LOCATION"C1873"
BOM_COST"VR_SYSTEM "
CDS_LIB"pure_quanta"
CDS_LOCATION"C1873"
$SEC"1"
CDS_SEC"1";
"B"
$PN"2"15;
"A"
$PN"1"11;
%"UNIVERSAL_GND"
"1","(9600,1275)","0","logical_power","I309";
;
HDL_POWER"GND"
CDS_LIB"logical_power";
"A"15;
%"UNIVERSAL_GND"
"1","(9350,775)","0","logical_power","I310";
;
HDL_POWER"GND"
CDS_LIB"logical_power";
"A"16;
%"Q_RES"
"1","(11000,250)","0","pure_quanta","I312";
;
PART_NUMBER"CS00002JB13"
VALUE"0"
TOLERANCE"5%"
WATTAGE"1/16W"
MATERIAL"CHIP"
PACK_TYPE"0402LF"
$LOCATION"R5377"
CDS_LIB"pure_quanta"
CDS_LOCATION"R5377"
$SEC"1"
CDS_SEC"1";
"B"
$PN"2"76;
"A"
$PN"1"44;
%"UNIVERSAL_GND"
"1","(9850,-400)","0","logical_power","I313";
;
HDL_POWER"GND"
CDS_LIB"logical_power";
"A"12;
%"74LVC1G126SE7"
"1","(9350,1175)","0","pure_quanta","I315";
;
PART_NUMBER"AL1G0126009"
VALUE"74LVC1G126SE-7"
PART_TYPE"SMLF"
MATERIAL"IC"
$LOCATION"U239"
NEEDS_NO_SIZE"TRUE"
CDS_LMAN_SYM_OUTLINE"-100,100,100,-100"
CDS_LIB"pure_quanta"
CDS_LOCATION"U239"
$SEC"1"
CDS_SEC"1";
"OE"
$PN"1"72;
"GND"
$PN"3"16;
"VCC"
$PN"5"11;
"Y"
$PN"4"39;
"A"
$PN"2"71;
%"Q_RES"
"2","(7650,1525)","0","pure_quanta","I317";
;
PART_NUMBER"CS24702FB06"
PACK_TYPE"0402LF"
MATERIAL"CHIP"
WATTAGE"1/16W"
TOLERANCE"1%"
VALUE"4.7K"
$LOCATION"R3295"
CDS_LIB"pure_quanta"
CDS_LOCATION"R3295"
$SEC"1"
CDS_SEC"1";
"A"
$PN"1"9;
"B"
$PN"2"71;
%"Q_RES"
"1","(7075,1225)","0","pure_quanta","I320";
;
PART_NUMBER"CS00002JB13"
VALUE"0"
MATERIAL"CHIP"
TOLERANCE"5%"
$LOCATION"R3294"
CDS_LIB"pure_quanta"
WATTAGE"1/16W"
PACK_TYPE"0402LF"
CDS_LOCATION"R3294"
$SEC"1"
CDS_SEC"1";
"B"
$PN"2"71;
"A"
$PN"1"69;
%"UNIVERSAL_POWER"
"1","(8625,625)","0","logical_power","I323";
;
HDL_POWER"P3V3_AUX"
CDS_LIB"logical_power";
"A"2;
%"Q_RES"
"2","(8625,300)","0","pure_quanta","I324";
;
PART_NUMBER"CS24702FB06"
WATTAGE"1/16W"
PACK_TYPE"0402LF"
VALUE"4.7K"
MATERIAL"CHIP"
TOLERANCE"1%"
$LOCATION"R3296"
CDS_LIB"pure_quanta"
CDS_LOCATION"R3296"
$SEC"1"
CDS_SEC"1";
"A"
$PN"1"2;
"B"
$PN"2"54;
%"UNIVERSAL_POWER"
"1","(8050,-200)","0","logical_power","I325";
;
HDL_POWER"P3V3_AUX"
CDS_LIB"logical_power";
"A"7;
%"Q_CAP"
"1","(8050,-750)","0","pure_quanta","I326";
;
PART_NUMBER"CH5104KEB02"
PACK_TYPE"C0402"
MATERIAL"X6S"
VALUE"1UF"
TOLERANCE"10%"
VOLTAGE"25V"
$LOCATION"C2007"
CDS_LIB"pure_quanta"
BOM_COST"VR_SYSTEM "
CDS_LOCATION"C2007"
$SEC"1"
CDS_SEC"1";
"B"
$PN"2"13;
"A"
$PN"1"7;
%"SN74LVC2G07DCKR"
"1","(7675,-400)","0","pure_quanta","I327";
;
PART_NUMBER"AL002G07006"
PACK_TYPE"SMLF"
MATERIAL"IC"
VALUE"SN74LVC2G07DCKR"
$LOCATION"U259"
CDS_LIB"pure_quanta"
NEEDS_NO_SIZE"TRUE"
CDS_LOCATION"U259"
$SEC"1"
CDS_SEC"1";
"VCC"
$PN"5"7;
"GND"
$PN"2"17;
"2Y"
$PN"4"42;
"1Y"
$PN"6"54;
"2A"
$PN"3"74;
"1A"
$PN"1"73;
%"UNIVERSAL_GND"
"1","(7250,-600)","0","logical_power","I328";
;
HDL_POWER"GND"
CDS_LIB"logical_power";
"A"17;
%"Q_RES"
"2","(10725,-250)","0","pure_quanta","I337";
;
PART_NUMBER"CS24702JB10"
MATERIAL"CHIP"
VALUE"4.7K"
TOLERANCE"5%"
WATTAGE"1/16W"
PACK_TYPE"0402LF"
$LOCATION"R2121"
CDS_LIB"pure_quanta"
CDS_LOCATION"R2121"
$SEC"1"
CDS_SEC"1";
"A"
$PN"1"1;
"B"
$PN"2"42;
%"UNIVERSAL_POWER"
"1","(10725,-25)","0","logical_power","I338";
;
HDL_POWER"P3V3_AUX"
CDS_LIB"logical_power";
"A"1;
%"UNIVERSAL_POWER"
"1","(7650,1775)","0","logical_power","I341";
;
HDL_POWER"P3V3_M2_0"
CDS_LIB"logical_power";
"A"9;
%"MOSFET_NCH_DUAL"
"1","(9800,-50)","0","pure_quanta","I342";
;
PART_NUMBER"BAM138K0003"
MATERIAL"IC"
VALUE"PJT138K"
PART_TYPE"SMLF"
LOCATION"Q95"
NEEDS_NO_SIZE"TRUE"
CDS_LMAN_SYM_OUTLINE"-150,150,150,-150"
CDS_LIB"pure_quanta"
$SEC"1"
CDS_SEC"1";
"D1"
$PN"6"44;
"G1"
$PN"2"54;
"S1"
$PN"1"12;
%"MOSFET_NCH_DUAL"
"2","(10100,-775)","0","pure_quanta","I343";
;
PART_NUMBER"BAM138K0003"
PART_TYPE"SMLF"
VALUE"PJT138K"
MATERIAL"IC"
LOCATION"Q95"
CDS_LIB"pure_quanta"
CDS_LMAN_SYM_OUTLINE"-150,150,150,-150"
NEEDS_NO_SIZE"TRUE"
$SEC"2"
CDS_SEC"2";
"S2"
$PN"4"56;
"G2"
$PN"5"55;
"D2"
$PN"3"57;
%"Q_RES"
"1","(11150,-450)","0","pure_quanta","I344";
;
PART_NUMBER"CS03322FB03"
TOLERANCE"1%"
VALUE"33.2"
MATERIAL"CHIP"
LOCATION"R2113"
CDS_LIB"pure_quanta"
PACK_TYPE"0402LF"
WATTAGE"1/16W"
$SEC"1"
CDS_SEC"1";
"B"
$PN"2"43;
"A"
$PN"1"42;
%"Q_CAP"
"1","(11275,4275)","0","pure_quanta","I88";
;
PART_NUMBER"CH6221ME900"
PACK_TYPE"C0603"
MATERIAL"X6S"
TOLERANCE"20%"
VALUE"22UF"
VOLTAGE"6.3V"
LOCATION"C1920"
CDS_LIB"pure_quanta"
$SEC"1"
CDS_SEC"1";
"B"
$PN"2"20;
"A"
$PN"1"4;
%"UNIVERSAL_POWER"
"1","(11275,4650)","0","logical_power","I89";
;
HDL_POWER"P3V3_M2_0"
CDS_LIB"logical_power";
"A"4;
%"Q_CAP"
"1","(11675,4275)","0","pure_quanta","I90";
;
PART_NUMBER"CH6221ME900"
VALUE"22UF"
VOLTAGE"6.3V"
PACK_TYPE"C0603"
MATERIAL"X6S"
TOLERANCE"20%"
LOCATION"C1921"
CDS_LIB"pure_quanta"
$SEC"1"
CDS_SEC"1";
"B"
$PN"2"20;
"A"
$PN"1"4;
%"Q_CAP"
"1","(12075,4275)","0","pure_quanta","I96";
;
PART_NUMBER"CH6221ME900"
MATERIAL"X6S"
PACK_TYPE"C0603"
VOLTAGE"6.3V"
TOLERANCE"20%"
VALUE"22UF"
LOCATION"C1922"
CDS_LIB"pure_quanta"
$SEC"1"
CDS_SEC"1";
"B"
$PN"2"20;
"A"
$PN"1"4;
%"Q_CAP"
"1","(12475,4275)","0","pure_quanta","I97";
;
PART_NUMBER"CH4104K1B00"
PACK_TYPE"0402"
TOLERANCE"10%"
MATERIAL"X7R"
VALUE"0.1UF"
VOLTAGE"25V"
LOCATION"C1923"
CDS_LIB"pure_quanta"
$SEC"1"
CDS_SEC"1";
"B"
$PN"2"20;
"A"
$PN"1"4;
%"Q_CAP"
"1","(12875,4275)","0","pure_quanta","I98";
;
PART_NUMBER"CH4104K1B00"
TOLERANCE"10%"
VOLTAGE"25V"
MATERIAL"X7R"
VALUE"0.1UF"
PACK_TYPE"0402"
LOCATION"C1924"
CDS_LIB"pure_quanta"
$SEC"1"
CDS_SEC"1";
"B"
$PN"2"20;
"A"
$PN"1"4;
%"UNIVERSAL_GND"
"1","(13275,3925)","0","logical_power","I99";
;
CATEGORY"LED"
HDL_POWER"GND"
CDS_LIB"logical_power";
"A"20;
END.
